(kicad_pcb
	(version 20260206)
	(generator "pcbnew")
	(generator_version "10.0")
	(general
		(thickness 1.6)
		(legacy_teardrops no)
	)
	(paper "A4")
	(title_block
		(title "04192023_DAF0TMB3IC0_F0TG_MB_C_brd_V02_OCP.brd")
		(comment 1 "Grand Teton / footprint 3955 of 8354 (U25), pads 1427-1537 of 6102")
	)
	(layers
		(0 "F.Cu" signal "TOP")
		(4 "In1.Cu" signal "GND")
		(6 "In2.Cu" signal "IN1")
		(8 "In3.Cu" signal "GND1")
		(10 "In4.Cu" signal "IN2")
		(12 "In5.Cu" signal "GND2")
		(14 "In6.Cu" signal "IN3")
		(16 "In7.Cu" signal "GND3")
		(18 "In8.Cu" signal "VCC")
		(20 "In9.Cu" signal "VCC1")
		(22 "In10.Cu" signal "GND4")
		(24 "In11.Cu" signal "IN4")
		(26 "In12.Cu" signal "GND5")
		(28 "In13.Cu" signal "IN5")
		(30 "In14.Cu" signal "GND6")
		(32 "In15.Cu" signal "IN6")
		(34 "In16.Cu" signal "GND7")
		(2 "B.Cu" signal "BOTTOM")
		(9 "F.Adhes" user "F.Adhesive")
		(11 "B.Adhes" user "B.Adhesive")
		(13 "F.Paste" user "Package Geometry/Pastemask Top")
		(15 "B.Paste" user "Package Geometry/Pastemask Bottom")
		(5 "F.SilkS" user "Ref Des/Silkscreen Top")
		(7 "B.SilkS" user "Ref Des/Silkscreen Bottom")
		(1 "F.Mask" user "Board Geometry/Soldermask Top")
		(3 "B.Mask" user "Board Geometry/Soldermask Bottom")
		(17 "Dwgs.User" user "User.Drawings")
		(19 "Cmts.User" user "User.Comments")
		(21 "Eco1.User" user "User.Eco1")
		(23 "Eco2.User" user "User.Eco2")
		(25 "Edge.Cuts" user "Board Geometry/Outline")
		(27 "Margin" user)
		(31 "F.CrtYd" user "Package Geometry/Place Bound Top")
		(29 "B.CrtYd" user "Package Geometry/Place Bound Bottom")
		(35 "F.Fab" user "Ref Des/Assembly Top")
		(33 "B.Fab" user "Ref Des/Assembly Bottom")
	)
	(footprint ""
		(layer "F.Cu")
		(at 359.867962 -258.880102 180)
		(property "Reference" "U25"
			(at -45.78477 -62.086744 0)
			(unlocked yes)
			(layer "F.SilkS")
			(effects
				(font
					(size 0.7874 0.5842)
					(thickness 0.1524)
				)
			)
		)
		(property "Value" ""
			(at 0 0 180)
			(layer "F.Fab")
			(effects
				(font
					(size 1.27 1.27)
				)
			)
		)
		(duplicate_pad_numbers_are_jumpers no)
		(pad "AY14" smd circle
			(at -22.409912 -5.219954 180)
			(size 0.450088 0.450088)
			(layers "F.Cu" "F.Mask" "F.Paste")
			(net "M_H_CPU0_SA_CA<2>")
		)
		(pad "AY15" smd circle
			(at -21.470112 -5.219954 180)
			(size 0.450088 0.450088)
			(layers "F.Cu" "F.Mask" "F.Paste")
			(net "GND")
		)
		(pad "AY16" smd circle
			(at -20.530058 -5.219954 180)
			(size 0.450088 0.450088)
			(layers "F.Cu" "F.Mask" "F.Paste")
			(net "M_J_CPU0_SA_CA<1>")
		)
		(pad "AY17" smd circle
			(at -19.590004 -5.219954 180)
			(size 0.450088 0.450088)
			(layers "F.Cu" "F.Mask" "F.Paste")
			(net "GND")
		)
		(pad "AY18" smd circle
			(at -18.64995 -5.219954 180)
			(size 0.450088 0.450088)
			(layers "F.Cu" "F.Mask" "F.Paste")
			(net "M_J_CPU0_SA_CA<2>")
		)
		(pad "AY19" smd circle
			(at -17.709896 -5.219954 180)
			(size 0.450088 0.450088)
			(layers "F.Cu" "F.Mask" "F.Paste")
			(net "GND")
		)
		(pad "AY20" smd circle
			(at -16.770096 -5.219954 180)
			(size 0.450088 0.450088)
			(layers "F.Cu" "F.Mask" "F.Paste")
			(net "M_I_CPU0_SA_CA<1>")
		)
		(pad "AY21" smd circle
			(at -15.830042 -5.219954 180)
			(size 0.450088 0.450088)
			(layers "F.Cu" "F.Mask" "F.Paste")
			(net "M_I_CPU0_SA_CA<2>")
		)
		(pad "AY22" smd circle
			(at -14.889988 -5.219954 180)
			(size 0.450088 0.450088)
			(layers "F.Cu" "F.Mask" "F.Paste")
			(net "PVDDCR_SOC_P0")
		)
		(pad "AY23" smd circle
			(at -13.949934 -5.219954 180)
			(size 0.450088 0.450088)
			(layers "F.Cu" "F.Mask" "F.Paste")
			(net "GND")
		)
		(pad "AY24" smd circle
			(at -13.00988 -5.219954 180)
			(size 0.450088 0.450088)
			(layers "F.Cu" "F.Mask" "F.Paste")
			(net "PVDDCR_SOC_P0")
		)
		(pad "AY25" smd circle
			(at -12.07008 -5.219954 180)
			(size 0.450088 0.450088)
			(layers "F.Cu" "F.Mask" "F.Paste")
			(net "GND")
		)
		(pad "AY26" smd circle
			(at -11.130026 -5.219954 180)
			(size 0.450088 0.450088)
			(layers "F.Cu" "F.Mask" "F.Paste")
			(net "PVDDCR_SOC_P0")
		)
		(pad "AY27" smd circle
			(at -10.189972 -5.219954 180)
			(size 0.450088 0.450088)
			(layers "F.Cu" "F.Mask" "F.Paste")
			(net "GND")
		)
		(pad "AY28" smd circle
			(at -9.249918 -5.219954 180)
			(size 0.450088 0.450088)
			(layers "F.Cu" "F.Mask" "F.Paste")
			(net "PVDDCR_SOC_P0")
		)
		(pad "AY48" smd circle
			(at 9.549892 -5.219954 180)
			(size 0.450088 0.450088)
			(layers "F.Cu" "F.Mask" "F.Paste")
			(net "GND")
		)
		(pad "AY49" smd circle
			(at 10.489946 -5.219954 180)
			(size 0.450088 0.450088)
			(layers "F.Cu" "F.Mask" "F.Paste")
			(net "PVDDCR_SOC_P0")
		)
		(pad "AY50" smd circle
			(at 11.43 -5.219954 180)
			(size 0.450088 0.450088)
			(layers "F.Cu" "F.Mask" "F.Paste")
			(net "GND")
		)
		(pad "AY51" smd circle
			(at 12.370054 -5.219954 180)
			(size 0.450088 0.450088)
			(layers "F.Cu" "F.Mask" "F.Paste")
			(net "PVDD18_S5_P0")
		)
		(pad "AY52" smd circle
			(at 13.310108 -5.219954 180)
			(size 0.450088 0.450088)
			(layers "F.Cu" "F.Mask" "F.Paste")
			(net "GND")
		)
		(pad "AY53" smd circle
			(at 14.249908 -5.219954 180)
			(size 0.450088 0.450088)
			(layers "F.Cu" "F.Mask" "F.Paste")
			(net "PVDD18_S5_P0")
		)
		(pad "AY54" smd circle
			(at 15.189962 -5.219954 180)
			(size 0.450088 0.450088)
			(layers "F.Cu" "F.Mask" "F.Paste")
			(net "GND")
		)
		(pad "AY55" smd circle
			(at 16.130016 -5.219954 180)
			(size 0.450088 0.450088)
			(layers "F.Cu" "F.Mask" "F.Paste")
			(net "M_C_CPU0_SA_CA<2>")
		)
		(pad "AY56" smd circle
			(at 17.07007 -5.219954 180)
			(size 0.450088 0.450088)
			(layers "F.Cu" "F.Mask" "F.Paste")
			(net "M_C_CPU0_SA_CA<1>")
		)
		(pad "AY57" smd circle
			(at 18.010124 -5.219954 180)
			(size 0.450088 0.450088)
			(layers "F.Cu" "F.Mask" "F.Paste")
			(net "GND")
		)
		(pad "AY58" smd circle
			(at 18.949924 -5.219954 180)
			(size 0.450088 0.450088)
			(layers "F.Cu" "F.Mask" "F.Paste")
			(net "M_D_CPU0_SA_CA<2>")
		)
		(pad "AY59" smd circle
			(at 19.889978 -5.219954 180)
			(size 0.450088 0.450088)
			(layers "F.Cu" "F.Mask" "F.Paste")
			(net "GND")
		)
		(pad "AY60" smd circle
			(at 20.830032 -5.219954 180)
			(size 0.450088 0.450088)
			(layers "F.Cu" "F.Mask" "F.Paste")
			(net "M_D_CPU0_SA_CA<1>")
		)
		(pad "AY61" smd circle
			(at 21.770086 -5.219954 180)
			(size 0.450088 0.450088)
			(layers "F.Cu" "F.Mask" "F.Paste")
			(net "GND")
		)
		(pad "AY62" smd circle
			(at 22.709886 -5.219954 180)
			(size 0.450088 0.450088)
			(layers "F.Cu" "F.Mask" "F.Paste")
			(net "M_B_CPU0_SA_CA<2>")
		)
		(pad "AY63" smd circle
			(at 23.64994 -5.219954 180)
			(size 0.450088 0.450088)
			(layers "F.Cu" "F.Mask" "F.Paste")
			(net "M_B_CPU0_SA_CA<1>")
		)
		(pad "AY64" smd circle
			(at 24.589994 -5.219954 180)
			(size 0.450088 0.450088)
			(layers "F.Cu" "F.Mask" "F.Paste")
			(net "GND")
		)
		(pad "AY65" smd circle
			(at 25.530048 -5.219954 180)
			(size 0.450088 0.450088)
			(layers "F.Cu" "F.Mask" "F.Paste")
			(net "M_F_CPU0_SA_CA<2>")
		)
		(pad "AY66" smd circle
			(at 26.470102 -5.219954 180)
			(size 0.450088 0.450088)
			(layers "F.Cu" "F.Mask" "F.Paste")
			(net "GND")
		)
		(pad "AY67" smd circle
			(at 27.409902 -5.219954 180)
			(size 0.450088 0.450088)
			(layers "F.Cu" "F.Mask" "F.Paste")
			(net "M_F_CPU0_SA_CA<1>")
		)
		(pad "AY68" smd circle
			(at 28.349956 -5.219954 180)
			(size 0.450088 0.450088)
			(layers "F.Cu" "F.Mask" "F.Paste")
			(net "GND")
		)
		(pad "AY69" smd circle
			(at 29.29001 -5.219954 180)
			(size 0.450088 0.450088)
			(layers "F.Cu" "F.Mask" "F.Paste")
			(net "M_E_CPU0_SA_CA<2>")
		)
		(pad "AY70" smd circle
			(at 30.230064 -5.219954 180)
			(size 0.450088 0.450088)
			(layers "F.Cu" "F.Mask" "F.Paste")
			(net "M_E_CPU0_SA_CA<1>")
		)
		(pad "AY71" smd circle
			(at 31.170118 -5.219954 180)
			(size 0.450088 0.450088)
			(layers "F.Cu" "F.Mask" "F.Paste")
			(net "GND")
		)
		(pad "AY72" smd circle
			(at 32.109918 -5.219954 180)
			(size 0.450088 0.450088)
			(layers "F.Cu" "F.Mask" "F.Paste")
			(net "M_A_CPU0_SA_CA<2>")
		)
		(pad "AY73" smd circle
			(at 33.049972 -5.219954 180)
			(size 0.450088 0.450088)
			(layers "F.Cu" "F.Mask" "F.Paste")
			(net "GND")
		)
		(pad "AY74" smd circle
			(at 33.990026 -5.219954 180)
			(size 0.450088 0.450088)
			(layers "F.Cu" "F.Mask" "F.Paste")
			(net "M_A_CPU0_SA_CA<1>")
		)
		(pad "B3" smd circle
			(at -32.749998 -35.999928 180)
			(size 0.450088 0.450088)
			(layers "F.Cu" "F.Mask" "F.Paste")
			(net "VSENSE_PVDDCR_SOC_P0_DP")
		)
		(pad "B4" smd circle
			(at -31.809944 -35.999928 180)
			(size 0.450088 0.450088)
			(layers "F.Cu" "F.Mask" "F.Paste")
			(net "SMB_CPU0_3_R_SDA")
		)
		(pad "B5" smd circle
			(at -30.86989 -35.999928 180)
			(size 0.450088 0.450088)
			(layers "F.Cu" "F.Mask" "F.Paste")
			(net "PVDDCR_SOC_P0")
		)
		(pad "B6" smd circle
			(at -29.93009 -35.999928 180)
			(size 0.450088 0.450088)
			(layers "F.Cu" "F.Mask" "F.Paste")
			(net "CLK_100M_CPU0_CLK02_R_DP")
		)
		(pad "B7" smd circle
			(at -28.990036 -35.999928 180)
			(size 0.450088 0.450088)
			(layers "F.Cu" "F.Mask" "F.Paste")
			(net "GND")
		)
		(pad "B8" smd circle
			(at -28.049982 -35.999928 180)
			(size 0.450088 0.450088)
			(layers "F.Cu" "F.Mask" "F.Paste")
			(net "GND")
		)
		(pad "B9" smd circle
			(at -27.109928 -35.999928 180)
			(size 0.450088 0.450088)
			(layers "F.Cu" "F.Mask" "F.Paste")
			(net "CLK_100M_CPU0_CLK05_R_DP")
		)
		(pad "B10" smd circle
			(at -26.170128 -35.999928 180)
			(size 0.450088 0.450088)
			(layers "F.Cu" "F.Mask" "F.Paste")
			(net "GND")
		)
		(pad "B11" smd circle
			(at -25.230074 -35.999928 180)
			(size 0.450088 0.450088)
			(layers "F.Cu" "F.Mask" "F.Paste")
			(net "GND")
		)
		(pad "B12" smd circle
			(at -24.29002 -35.999928 180)
			(size 0.450088 0.450088)
			(layers "F.Cu" "F.Mask" "F.Paste")
			(net "CLK_100M_CPU0_CLK04_R_DP")
		)
		(pad "B13" smd circle
			(at -23.349966 -35.999928 180)
			(size 0.450088 0.450088)
			(layers "F.Cu" "F.Mask" "F.Paste")
			(net "GND")
		)
		(pad "B14" smd circle
			(at -22.409912 -35.999928 180)
			(size 0.450088 0.450088)
			(layers "F.Cu" "F.Mask" "F.Paste")
			(net "SMB_CPU0_SEC_SCL")
		)
		(pad "B15" smd circle
			(at -21.470112 -35.999928 180)
			(size 0.450088 0.450088)
			(layers "F.Cu" "F.Mask" "F.Paste")
			(net "Net_1882")
		)
		(pad "B16" smd circle
			(at -20.530058 -35.999928 180)
			(size 0.450088 0.450088)
			(layers "F.Cu" "F.Mask" "F.Paste")
			(net "Net_1875")
		)
		(pad "B17" smd circle
			(at -19.590004 -35.999928 180)
			(size 0.450088 0.450088)
			(layers "F.Cu" "F.Mask" "F.Paste")
			(net "JTAG_CPU0_TCK")
		)
		(pad "B18" smd circle
			(at -18.64995 -35.999928 180)
			(size 0.450088 0.450088)
			(layers "F.Cu" "F.Mask" "F.Paste")
			(net "GND")
		)
		(pad "B19" smd circle
			(at -17.709896 -35.999928 180)
			(size 0.450088 0.450088)
			(layers "F.Cu" "F.Mask" "F.Paste")
			(net "PVDDCR_CPU0_P0")
		)
		(pad "B20" smd circle
			(at -16.770096 -35.999928 180)
			(size 0.450088 0.450088)
			(layers "F.Cu" "F.Mask" "F.Paste")
			(net "PVDDCR_CPU0_P0")
		)
		(pad "B21" smd circle
			(at -15.830042 -35.999928 180)
			(size 0.450088 0.450088)
			(layers "F.Cu" "F.Mask" "F.Paste")
			(net "SVID_PVDDCR_CPU0_P0_SVTO")
		)
		(pad "B22" smd circle
			(at -14.889988 -35.999928 180)
			(size 0.450088 0.450088)
			(layers "F.Cu" "F.Mask" "F.Paste")
			(net "PVDDCR_CPU0_P0")
		)
		(pad "B23" smd circle
			(at -13.949934 -35.999928 180)
			(size 0.450088 0.450088)
			(layers "F.Cu" "F.Mask" "F.Paste")
			(net "PVDDCR_CPU0_P0")
		)
		(pad "B24" smd circle
			(at -13.00988 -35.999928 180)
			(size 0.450088 0.450088)
			(layers "F.Cu" "F.Mask" "F.Paste")
			(net "GND")
		)
		(pad "B25" smd circle
			(at -12.07008 -35.999928 180)
			(size 0.450088 0.450088)
			(layers "F.Cu" "F.Mask" "F.Paste")
			(net "PVDDCR_CPU0_P0")
		)
		(pad "B26" smd circle
			(at -11.130026 -35.999928 180)
			(size 0.450088 0.450088)
			(layers "F.Cu" "F.Mask" "F.Paste")
			(net "PVDDCR_CPU0_P0")
		)
		(pad "B27" smd circle
			(at -10.189972 -35.999928 180)
			(size 0.450088 0.450088)
			(layers "F.Cu" "F.Mask" "F.Paste")
			(net "GND")
		)
		(pad "B28" smd circle
			(at -9.249918 -35.999928 180)
			(size 0.450088 0.450088)
			(layers "F.Cu" "F.Mask" "F.Paste")
			(net "PVDDCR_CPU0_P0")
		)
		(pad "B29" smd circle
			(at -8.310118 -35.999928 180)
			(size 0.450088 0.450088)
			(layers "F.Cu" "F.Mask" "F.Paste")
			(net "PVDDCR_CPU0_P0")
		)
		(pad "B30" smd circle
			(at -7.370064 -35.999928 180)
			(size 0.450088 0.450088)
			(layers "F.Cu" "F.Mask" "F.Paste")
			(net "GND")
		)
		(pad "B31" smd circle
			(at -6.43001 -35.999928 180)
			(size 0.450088 0.450088)
			(layers "F.Cu" "F.Mask" "F.Paste")
			(net "PVDDCR_CPU0_P0")
		)
		(pad "B32" smd circle
			(at -5.489956 -35.999928 180)
			(size 0.450088 0.450088)
			(layers "F.Cu" "F.Mask" "F.Paste")
			(net "PVDDCR_CPU0_P0")
		)
		(pad "B33" smd circle
			(at -4.549902 -35.999928 180)
			(size 0.450088 0.450088)
			(layers "F.Cu" "F.Mask" "F.Paste")
			(net "GND")
		)
		(pad "B34" smd circle
			(at -3.610102 -35.999928 180)
			(size 0.450088 0.450088)
			(layers "F.Cu" "F.Mask" "F.Paste")
			(net "PVDDCR_CPU0_P0")
		)
		(pad "B35" smd circle
			(at -2.670048 -35.999928 180)
			(size 0.450088 0.450088)
			(layers "F.Cu" "F.Mask" "F.Paste")
			(net "PVDDCR_CPU0_P0")
		)
		(pad "B36" smd circle
			(at -1.729994 -35.999928 180)
			(size 0.450088 0.450088)
			(layers "F.Cu" "F.Mask" "F.Paste")
			(net "Net_1954")
		)
		(pad "B37" smd circle
			(at -0.78994 -35.999928 180)
			(size 0.450088 0.450088)
			(layers "F.Cu" "F.Mask" "F.Paste")
			(net "GND")
		)
		(pad "B39" smd circle
			(at 1.089914 -35.999928 180)
			(size 0.450088 0.450088)
			(layers "F.Cu" "F.Mask" "F.Paste")
			(net "GND")
		)
		(pad "B40" smd circle
			(at 2.029968 -35.999928 180)
			(size 0.450088 0.450088)
			(layers "F.Cu" "F.Mask" "F.Paste")
			(net "Net_1912")
		)
		(pad "B41" smd circle
			(at 2.970022 -35.999928 180)
			(size 0.450088 0.450088)
			(layers "F.Cu" "F.Mask" "F.Paste")
			(net "PVDDCR_CPU0_P0")
		)
		(pad "B42" smd circle
			(at 3.910076 -35.999928 180)
			(size 0.450088 0.450088)
			(layers "F.Cu" "F.Mask" "F.Paste")
			(net "PVDDCR_CPU0_P0")
		)
		(pad "B43" smd circle
			(at 4.849876 -35.999928 180)
			(size 0.450088 0.450088)
			(layers "F.Cu" "F.Mask" "F.Paste")
			(net "GND")
		)
		(pad "B44" smd circle
			(at 5.78993 -35.999928 180)
			(size 0.450088 0.450088)
			(layers "F.Cu" "F.Mask" "F.Paste")
			(net "PVDDCR_CPU0_P0")
		)
		(pad "B45" smd circle
			(at 6.729984 -35.999928 180)
			(size 0.450088 0.450088)
			(layers "F.Cu" "F.Mask" "F.Paste")
			(net "PVDDCR_CPU0_P0")
		)
		(pad "B46" smd circle
			(at 7.670038 -35.999928 180)
			(size 0.450088 0.450088)
			(layers "F.Cu" "F.Mask" "F.Paste")
			(net "GND")
		)
		(pad "B47" smd circle
			(at 8.610092 -35.999928 180)
			(size 0.450088 0.450088)
			(layers "F.Cu" "F.Mask" "F.Paste")
			(net "PVDDCR_CPU0_P0")
		)
		(pad "B48" smd circle
			(at 9.549892 -35.999928 180)
			(size 0.450088 0.450088)
			(layers "F.Cu" "F.Mask" "F.Paste")
			(net "PVDDCR_CPU0_P0")
		)
		(pad "B49" smd circle
			(at 10.489946 -35.999928 180)
			(size 0.450088 0.450088)
			(layers "F.Cu" "F.Mask" "F.Paste")
			(net "GND")
		)
		(pad "B50" smd circle
			(at 11.43 -35.999928 180)
			(size 0.450088 0.450088)
			(layers "F.Cu" "F.Mask" "F.Paste")
			(net "PVDDCR_CPU0_P0")
		)
		(pad "B51" smd circle
			(at 12.370054 -35.999928 180)
			(size 0.450088 0.450088)
			(layers "F.Cu" "F.Mask" "F.Paste")
			(net "PVDDCR_CPU0_P0")
		)
		(pad "B52" smd circle
			(at 13.310108 -35.999928 180)
			(size 0.450088 0.450088)
			(layers "F.Cu" "F.Mask" "F.Paste")
			(net "GND")
		)
		(pad "B53" smd circle
			(at 14.249908 -35.999928 180)
			(size 0.450088 0.450088)
			(layers "F.Cu" "F.Mask" "F.Paste")
			(net "PVDDCR_CPU0_P0")
		)
		(pad "B54" smd circle
			(at 15.189962 -35.999928 180)
			(size 0.450088 0.450088)
			(layers "F.Cu" "F.Mask" "F.Paste")
			(net "PVDDCR_CPU0_P0")
		)
		(pad "B55" smd circle
			(at 16.130016 -35.999928 180)
			(size 0.450088 0.450088)
			(layers "F.Cu" "F.Mask" "F.Paste")
			(net "GND")
		)
		(pad "B56" smd circle
			(at 17.07007 -35.999928 180)
			(size 0.450088 0.450088)
			(layers "F.Cu" "F.Mask" "F.Paste")
			(net "PVDDCR_CPU0_P0")
		)
		(pad "B57" smd circle
			(at 18.010124 -35.999928 180)
			(size 0.450088 0.450088)
			(layers "F.Cu" "F.Mask" "F.Paste")
			(net "PVDDCR_CPU0_P0")
		)
		(pad "B58" smd circle
			(at 18.949924 -35.999928 180)
			(size 0.450088 0.450088)
			(layers "F.Cu" "F.Mask" "F.Paste")
			(net "TP_CPU0_TEST47_IOD0")
		)
		(pad "B59" smd circle
			(at 19.889978 -35.999928 180)
			(size 0.450088 0.450088)
			(layers "F.Cu" "F.Mask" "F.Paste")
			(net "GND")
		)
		(pad "B60" smd circle
			(at 20.830032 -35.999928 180)
			(size 0.450088 0.450088)
			(layers "F.Cu" "F.Mask" "F.Paste")
			(net "TP_CPU0_TEST47_CCD0")
		)
		(pad "B61" smd circle
			(at 21.770086 -35.999928 180)
			(size 0.450088 0.450088)
			(layers "F.Cu" "F.Mask" "F.Paste")
			(net "TP_CPU0_TEST50_IOD")
		)
		(pad "B62" smd circle
			(at 22.709886 -35.999928 180)
			(size 0.450088 0.450088)
			(layers "F.Cu" "F.Mask" "F.Paste")
			(net "GND")
		)
		(pad "B63" smd circle
			(at 23.64994 -35.999928 180)
			(size 0.450088 0.450088)
			(layers "F.Cu" "F.Mask" "F.Paste")
			(net "CPU0_FORCE_SELFREFRESH")
		)
		(pad "B64" smd circle
			(at 24.589994 -35.999928 180)
			(size 0.450088 0.450088)
			(layers "F.Cu" "F.Mask" "F.Paste")
			(net "CPU0_NV_SAVE_N")
		)
		(pad "B65" smd circle
			(at 25.530048 -35.999928 180)
			(size 0.450088 0.450088)
			(layers "F.Cu" "F.Mask" "F.Paste")
			(net "GND")
		)
		(pad "B66" smd circle
			(at 26.470102 -35.999928 180)
			(size 0.450088 0.450088)
			(layers "F.Cu" "F.Mask" "F.Paste")
			(net "PRSNT_CPU0_N")
		)
		(pad "B67" smd circle
			(at 27.409902 -35.999928 180)
			(size 0.450088 0.450088)
			(layers "F.Cu" "F.Mask" "F.Paste")
			(net "RST_CPU0_RESETL_N")
		)
		(pad "B68" smd circle
			(at 28.349956 -35.999928 180)
			(size 0.450088 0.450088)
			(layers "F.Cu" "F.Mask" "F.Paste")
			(net "GND")
		)
		(pad "B69" smd circle
			(at 29.29001 -35.999928 180)
			(size 0.450088 0.450088)
			(layers "F.Cu" "F.Mask" "F.Paste")
			(net "CPU0_CORETYPE1")
		)
		(pad "B70" smd circle
			(at 30.230064 -35.999928 180)
			(size 0.450088 0.450088)
			(layers "F.Cu" "F.Mask" "F.Paste")
			(net "GND")
		)
		(pad "B71" smd circle
			(at 31.170118 -35.999928 180)
			(size 0.450088 0.450088)
			(layers "F.Cu" "F.Mask" "F.Paste")
			(net "I3C_0_SPD_DDRAF_CPU0_R_SDA")
		)
		(pad "B72" smd circle
			(at 32.109918 -35.999928 180)
			(size 0.450088 0.450088)
			(layers "F.Cu" "F.Mask" "F.Paste")
			(net "SMB_CPU0_2_R_SDA")
		)
	)
)
